# T6G (Grand Teton) — schematic netlist excerpt (pin names and nets, part order shuffled) for the footprints in the layout excerpt that follows; sources: Cadence DE-HDL packaged netlist, KiCad conversion of 04192023_DAF0TMB3IC0_F0TG_MB_C_brd_V02_OCP.brd

C6686  Q_CAP_DIFFBUS  DIFF BUS_0.22UF 6.3V 20% X6S  pkg C0201  page 330 : \1\ = P5E_CPU1_P1_TX_BUF_C_DN<12> ; \2\ = P5E_CPU1_P1_TX_BUF_DN<12>
C2201  Q_CAP  22UF 4V 20% X6S  pkg C0402  page 69 : A = PVDDCR_CPU1_P0 ; B = GND
C597  Q_CAP  1UF 4V 20% X6S  pkg 0201  page 290 : A = P1V8_CPU0_RT1_1A ; B = GND

(kicad_pcb
	(version 20260206)
	(generator "pcbnew")
	(generator_version "10.0")
	(general
		(thickness 1.6)
		(legacy_teardrops no)
	)
	(paper "A4")
	(title_block
		(title "04192023_DAF0TMB3IC0_F0TG_MB_C_brd_V02_OCP.brd")
		(comment 1 "Grand Teton / footprints 5526-5528 of 8354")
	)
	(layers
		(0 "F.Cu" signal "TOP")
		(4 "In1.Cu" signal "GND")
		(6 "In2.Cu" signal "IN1")
		(8 "In3.Cu" signal "GND1")
		(10 "In4.Cu" signal "IN2")
		(12 "In5.Cu" signal "GND2")
		(14 "In6.Cu" signal "IN3")
		(16 "In7.Cu" signal "GND3")
		(18 "In8.Cu" signal "VCC")
		(20 "In9.Cu" signal "VCC1")
		(22 "In10.Cu" signal "GND4")
		(24 "In11.Cu" signal "IN4")
		(26 "In12.Cu" signal "GND5")
		(28 "In13.Cu" signal "IN5")
		(30 "In14.Cu" signal "GND6")
		(32 "In15.Cu" signal "IN6")
		(34 "In16.Cu" signal "GND7")
		(2 "B.Cu" signal "BOTTOM")
		(9 "F.Adhes" user "F.Adhesive")
		(11 "B.Adhes" user "B.Adhesive")
		(13 "F.Paste" user "Package Geometry/Pastemask Top")
		(15 "B.Paste" user "Package Geometry/Pastemask Bottom")
		(5 "F.SilkS" user "Ref Des/Silkscreen Top")
		(7 "B.SilkS" user "Ref Des/Silkscreen Bottom")
		(1 "F.Mask" user "Board Geometry/Soldermask Top")
		(3 "B.Mask" user "Board Geometry/Soldermask Bottom")
		(17 "Dwgs.User" user "User.Drawings")
		(19 "Cmts.User" user "User.Comments")
		(21 "Eco1.User" user "User.Eco1")
		(23 "Eco2.User" user "User.Eco2")
		(25 "Edge.Cuts" user "Board Geometry/Outline")
		(27 "Margin" user)
		(31 "F.CrtYd" user "Package Geometry/Place Bound Top")
		(29 "B.CrtYd" user "Package Geometry/Place Bound Bottom")
		(35 "F.Fab" user "Ref Des/Assembly Top")
		(33 "B.Fab" user "Ref Des/Assembly Bottom")
	)
	(footprint ""
		(layer "B.Cu")
		(at 355.295454 -269.30731 180)
		(property "Reference" "C2201"
			(at 0 0 0)
			(layer "B.SilkS")
			(hide yes)
			(effects
				(font
					(size 1.27 1.27)
				)
				(justify mirror)
			)
		)
		(property "Value" ""
			(at 0 0 0)
			(layer "B.Fab")
			(effects
				(font
					(size 1.27 1.27)
				)
				(justify mirror)
			)
		)
		(duplicate_pad_numbers_are_jumpers no)
		(fp_line
			(start 0.7874 0.4064)
			(end 0.7874 -0.4064)
			(stroke
				(width 0.1524)
				(type default)
			)
			(layer "B.SilkS")
		)
		(fp_line
			(start 0.7874 -0.4064)
			(end -0.7874 -0.4064)
			(stroke
				(width 0.1524)
				(type default)
			)
			(layer "B.SilkS")
		)
		(fp_line
			(start -0.7874 0.4064)
			(end 0.7874 0.4064)
			(stroke
				(width 0.1524)
				(type default)
			)
			(layer "B.SilkS")
		)
		(fp_line
			(start -0.7874 -0.4064)
			(end -0.7874 0.4064)
			(stroke
				(width 0.1524)
				(type default)
			)
			(layer "B.SilkS")
		)
		(fp_line
			(start 0.67945 0.3048)
			(end 0.67945 -0.305054)
			(stroke
				(width 0.1)
				(type default)
			)
			(layer "B.Fab")
		)
		(fp_line
			(start 0.67945 -0.305054)
			(end 0.12065 -0.305054)
			(stroke
				(width 0.1)
				(type default)
			)
			(layer "B.Fab")
		)
		(fp_line
			(start 0.12065 0.3048)
			(end 0.67945 0.3048)
			(stroke
				(width 0.1)
				(type default)
			)
			(layer "B.Fab")
		)
		(fp_line
			(start 0.12065 0.2794)
			(end 0.12065 0.3048)
			(stroke
				(width 0.1)
				(type default)
			)
			(layer "B.Fab")
		)
		(fp_line
			(start 0.12065 -0.2794)
			(end -0.12065 -0.2794)
			(stroke
				(width 0.1)
				(type default)
			)
			(layer "B.Fab")
		)
		(fp_line
			(start 0.12065 -0.305054)
			(end 0.12065 -0.2794)
			(stroke
				(width 0.1)
				(type default)
			)
			(layer "B.Fab")
		)
		(fp_line
			(start -0.120396 0.3048)
			(end -0.120396 0.2794)
			(stroke
				(width 0.1)
				(type default)
			)
			(layer "B.Fab")
		)
		(fp_line
			(start -0.120396 0.2794)
			(end 0.12065 0.2794)
			(stroke
				(width 0.1)
				(type default)
			)
			(layer "B.Fab")
		)
		(fp_line
			(start -0.12065 -0.2794)
			(end -0.12065 -0.3048)
			(stroke
				(width 0.1)
				(type default)
			)
			(layer "B.Fab")
		)
		(fp_line
			(start -0.12065 -0.3048)
			(end -0.67945 -0.3048)
			(stroke
				(width 0.1)
				(type default)
			)
			(layer "B.Fab")
		)
		(fp_line
			(start -0.67945 0.3048)
			(end -0.120396 0.3048)
			(stroke
				(width 0.1)
				(type default)
			)
			(layer "B.Fab")
		)
		(fp_line
			(start -0.67945 -0.3048)
			(end -0.67945 0.3048)
			(stroke
				(width 0.1)
				(type default)
			)
			(layer "B.Fab")
		)
		(pad "1" smd circle
			(at 0.40005 0)
			(size 0 0)
			(layers "B.Cu" "B.Mask" "B.Paste")
			(net "PVDDCR_CPU1_P0")
		)
		(pad "2" smd circle
			(at -0.40005 0)
			(size 0 0)
			(layers "B.Cu" "B.Mask" "B.Paste")
			(net "GND")
		)
	)
	(footprint ""
		(layer "B.Cu")
		(at 86.059264 -408.517344 90)
		(property "Reference" "C6686"
			(at 0 0 90)
			(layer "B.SilkS")
			(hide yes)
			(effects
				(font
					(size 1.27 1.27)
				)
				(justify mirror)
			)
		)
		(property "Value" ""
			(at 0 0 90)
			(layer "B.Fab")
			(effects
				(font
					(size 1.27 1.27)
				)
				(justify mirror)
			)
		)
		(duplicate_pad_numbers_are_jumpers no)
		(fp_line
			(start 0.299974 -0.150114)
			(end -0.299974 -0.150114)
			(stroke
				(width 0.1)
				(type default)
			)
			(layer "B.Fab")
		)
		(fp_line
			(start -0.299974 -0.150114)
			(end -0.299974 0.150114)
			(stroke
				(width 0.1)
				(type default)
			)
			(layer "B.Fab")
		)
		(fp_line
			(start 0.299974 0.150114)
			(end 0.299974 -0.150114)
			(stroke
				(width 0.1)
				(type default)
			)
			(layer "B.Fab")
		)
		(fp_line
			(start -0.299974 0.150114)
			(end 0.299974 0.150114)
			(stroke
				(width 0.1)
				(type default)
			)
			(layer "B.Fab")
		)
		(pad "1" smd rect
			(at 0.2667 0 270)
			(size 0.3048 0.381)
			(layers "B.Cu" "B.Mask" "B.Paste")
			(net "P5E_CPU1_P1_TX_BUF_C_DN<12>")
		)
		(pad "2" smd rect
			(at -0.2667 0 270)
			(size 0.3048 0.381)
			(layers "B.Cu" "B.Mask" "B.Paste")
			(net "P5E_CPU1_P1_TX_BUF_DN<12>")
		)
	)
	(footprint ""
		(layer "B.Cu")
		(at 343.245948 -396.393162 -90)
		(property "Reference" "C597"
			(at 0 0 90)
			(layer "B.SilkS")
			(hide yes)
			(effects
				(font
					(size 1.27 1.27)
				)
				(justify mirror)
			)
		)
		(property "Value" ""
			(at 0 0 90)
			(layer "B.Fab")
			(effects
				(font
					(size 1.27 1.27)
				)
				(justify mirror)
			)
		)
		(duplicate_pad_numbers_are_jumpers no)
		(fp_line
			(start -0.299974 0.150114)
			(end 0.299974 0.150114)
			(stroke
				(width 0.1)
				(type default)
			)
			(layer "B.Fab")
		)
		(fp_line
			(start 0.299974 0.150114)
			(end 0.299974 -0.150114)
			(stroke
				(width 0.1)
				(type default)
			)
			(layer "B.Fab")
		)
		(fp_line
			(start -0.299974 -0.150114)
			(end -0.299974 0.150114)
			(stroke
				(width 0.1)
				(type default)
			)
			(layer "B.Fab")
		)
		(fp_line
			(start 0.299974 -0.150114)
			(end -0.299974 -0.150114)
			(stroke
				(width 0.1)
				(type default)
			)
			(layer "B.Fab")
		)
		(pad "1" smd rect
			(at 0.2667 0 90)
			(size 0.3048 0.381)
			(layers "B.Cu" "B.Mask" "B.Paste")
			(net "P1V8_CPU0_RT1_1A")
		)
		(pad "2" smd rect
			(at -0.2667 0 90)
			(size 0.3048 0.381)
			(layers "B.Cu" "B.Mask" "B.Paste")
			(net "GND")
		)
	)
)
